FILE_TYPE = CONNECTIVITY;
{Allegro Design Entry HDL 17.2-2016 S066 (3851973) 4/6/2020}
"PAGE_NUMBER" = 6;
0"NC";
1"XP3R3V_FPGA\g";
2"XP3R3V_FPGA\g";
3"XP3R3V_FPGA\g";
4"FPGA_IN_LM75B_INT1_N";
5"XP3R3V_FPGA\g";
6"FPGA_IN_LM75B_INT2_N";
7"FPGA_IN_LM75B_INT3_N";
8"SG\g";
9"SG\g";
10"XP3R3V_FPGA\g";
11"XP3R3V_FPGA\g";
12"SG\g";
13"SG\g";
14"XP3R3V_FPGA\g";
15"XP3R3V_FPGA\g";
16"SG\g";
17"SG\g";
18"XP3R3V_FPGA\g";
19"R_LM75B_3_I2C_SDA";
20"LM75B_I2C_SCL";
21"UN$6$LM75BDPTSSOP8$I81$A0";
22"UN$6$LM75BDPTSSOP8$I34$A0";
23"R_LM75B_2_I2C_SDA";
24"LM75B_I2C_SDA";
25"R_LM75B_1_I2C_SDA";
26"UN$6$LM75BDPTSSOP8$I34$A1";
27"UN$6$LM75BDPTSSOP8$I59$A0";
28"UN$6$LM75BDPTSSOP8$I81$A2";
29"UN$6$LM75BDPTSSOP8$I81$A1";
30"UN$6$LM75BDPTSSOP8$I59$A1";
31"UN$6$LM75BDPTSSOP8$I59$A2";
32"UN$6$LM75BDPTSSOP8$I34$A2";
%"RESISTOR"
"1","(-5600,1600)","0","passive","I100";
;
$LOCATION"R407"
CDS_LOCATION"R407"
$SEC"1"
CDS_SEC"1"
VALUE"33OHM"
PACKAGE"0402"
TOLERANCE"1%"
CDS_LIB"passive"
CDS_LMAN_SYM_OUTLINE"-50,50,100,-50"
CLS_PN"G155-133R0-01";
"1"
$PN"1"24;
"2"
$PN"2"19;
%"RESISTOR"
"2","(-5900,8150)","0","passive","I14";
;
$LOCATION"R20"
CDS_LOCATION"R20"
$SEC"1"
CDS_SEC"1"
PACKAGE"0402"
VALUE"4.7KOHM"
TOLERANCE"1%"
CDS_LMAN_SYM_OUTLINE"-50,50,50,-100"
CDS_LIB"passive"
CLS_PN"G155-14701-01";
"1"
$PN"1"10;
"2"
$PN"2"24;
%"RESISTOR"
"1","(-5350,7600)","0","passive","I15";
;
$LOCATION"R332"
CDS_LOCATION"R332"
$SEC"1"
CDS_SEC"1"
VALUE"33OHM"
PACKAGE"0402"
TOLERANCE"1%"
CLS_PN"G155-133R0-01"
CDS_LIB"passive"
CDS_LMAN_SYM_OUTLINE"-50,50,100,-50";
"1"
$PN"1"24;
"2"
$PN"2"25;
%"RESISTOR"
"2","(-5350,8150)","0","passive","I16";
;
$LOCATION"R21"
CDS_LOCATION"R21"
$SEC"1"
CDS_SEC"1"
VALUE"4.7KOHM"
PACKAGE"0402"
TOLERANCE"1%"
CLS_PN"G155-14701-01"
CDS_LIB"passive"
CDS_LMAN_SYM_OUTLINE"-50,50,50,-100";
"1"
$PN"1"10;
"2"
$PN"2"20;
%"GND_SG"
"1","(-3900,6450)","0","cls","I29";
;
HDL_POWER"SG"
BODY_TYPE"PLUMBING"
CDS_LMAN_SYM_OUTLINE"0,0,100,-50"
CDS_LIB"cls";
"SGND"8;
%"RESISTOR"
"2","(-3850,6900)","0","passive","I30";
;
$LOCATION"R334"
CDS_LOCATION"R334"
$SEC"1"
CDS_SEC"1"
PACKAGE"0402"
VALUE"1KOHM"
TOLERANCE"1%"
CLS_PN"G155-11001-01"
CDS_LIB"passive"
CDS_LMAN_SYM_OUTLINE"-50,50,50,-100";
"1"
$PN"1"32;
"2"
$PN"2"8;
%"RESISTOR"
"2","(-3850,8150)","0","passive","I31";
;
$LOCATION"R333"
CDS_LOCATION"R333"
$SEC"1"
CDS_SEC"1"
NO_ASSY"TRUE"
VALUE"4.7KOHM"
PACKAGE"0402"
TOLERANCE"1%"
CLS_PN"G155-14701-01"
CDS_LIB"passive"
CDS_LMAN_SYM_OUTLINE"-50,50,50,-100";
"1"
$PN"1"10;
"2"
$PN"2"32;
%"RESISTOR"
"2","(-3400,6900)","0","passive","I32";
;
$LOCATION"R336"
CDS_LOCATION"R336"
$SEC"1"
CDS_SEC"1"
VALUE"1KOHM"
PACKAGE"0402"
TOLERANCE"1%"
CLS_PN"G155-11001-01"
CDS_LIB"passive"
CDS_LMAN_SYM_OUTLINE"-50,50,50,-100";
"1"
$PN"1"26;
"2"
$PN"2"8;
%"RESISTOR"
"2","(-3020,6890)","0","passive","I33";
;
$LOCATION"R338"
CDS_LOCATION"R338"
$SEC"1"
CDS_SEC"1"
VALUE"1KOHM"
PACKAGE"0402"
TOLERANCE"1%"
CLS_PN"G155-11001-01"
CDS_LMAN_SYM_OUTLINE"-50,50,50,-100"
CDS_LIB"passive";
"1"
$PN"1"22;
"2"
$PN"2"8;
%"LM75BDP_TSSOP8"
"1","(-2700,7800)","0","interface","I34";
;
$LOCATION"U8"
CDS_LOCATION"U8"
$SEC"1"
CDS_SEC"1"
PART_NUMBER"LM75BDP,118"
CLS_PN"G220-10215-01"
CDS_LMAN_SYM_OUTLINE"0,0,500,-800"
CDS_LIB"interface";
"A0"
$PN"7"22;
"A1"
$PN"6"26;
"A2"
$PN"5"32;
"OS"
$PN"3"4;
"SCL"
$PN"2"20;
"SDA"
$PN"1"25;
%"RESISTOR"
"2","(-3400,8150)","0","passive","I35";
;
$LOCATION"R335"
CDS_LOCATION"R335"
$SEC"1"
CDS_SEC"1"
VALUE"4.7KOHM"
NO_ASSY"TRUE"
PACKAGE"0402"
TOLERANCE"1%"
CLS_PN"G155-14701-01"
CDS_LIB"passive"
CDS_LMAN_SYM_OUTLINE"-50,50,50,-100";
"1"
$PN"1"10;
"2"
$PN"2"26;
%"RESISTOR"
"2","(-3000,8150)","0","passive","I36";
;
$LOCATION"R337"
CDS_LOCATION"R337"
$SEC"1"
CDS_SEC"1"
VALUE"4.7KOHM"
PACKAGE"0402"
NO_ASSY"TRUE"
TOLERANCE"1%"
CLS_PN"G155-14701-01"
CDS_LMAN_SYM_OUTLINE"-50,50,50,-100"
CDS_LIB"passive";
"1"
$PN"1"10;
"2"
$PN"2"22;
%"CAPACITOR"
"1","(-1450,6400)","0","passive","I37";
;
$LOCATION"C39"
CDS_LOCATION"C39"
$SEC"1"
CDS_SEC"1"
PACKAGE"0402"
VOLTAGE"25V"
VALUE"0.1UF"
CLS_PN"G105-0B104-EK"
CDS_LMAN_SYM_OUTLINE"0,50,50,-50"
CDS_LIB"passive"
TOLERANCE"10%";
"2"
$PN"2"11;
"1"
$PN"1"9;
%"LM75BDP_TSSOP8"
"2","(-1050,7100)","5","interface","I38";
;
$LOCATION"U8"
CDS_LOCATION"U8"
$SEC"2"
CDS_SEC"2"
CLS_PN"G220-10215-01"
CDS_LMAN_SYM_OUTLINE"0,0,400,-700"
CDS_LIB"interface";
"GND"
$PN"4"9;
"VCC"
$PN"8"11;
%"RESISTOR"
"2","(-1350,7900)","0","passive","I41";
;
$LOCATION"R340"
CDS_LOCATION"R340"
$SEC"1"
CDS_SEC"1"
PACKAGE"0402"
VALUE"4.7KOHM"
CDS_LIB"passive"
CDS_LMAN_SYM_OUTLINE"-50,50,50,-100"
CLS_PN"G155-14701-01"
TOLERANCE"1%";
"1"
$PN"1"3;
"2"
$PN"2"4;
%"GND_SG"
"1","(-2100,6150)","0","cls","I45";
;
HDL_POWER"SG"
BODY_TYPE"PLUMBING"
CDS_LMAN_SYM_OUTLINE"0,0,100,-50"
CDS_LIB"cls";
"SGND"9;
%"VCC"
"1","(-5950,8550)","0","cls","I56";
;
HDL_POWER"XP3R3V_FPGA"
VOLTAGE"3.3V"
BODY_TYPE"PLUMBING"
CDS_LIB"cls"
CDS_LMAN_SYM_OUTLINE"-250,250,250,-250";
"$PIN0"10;
%"VCC"
"1","(-1400,8150)","0","cls","I57";
;
HDL_POWER"XP3R3V_FPGA"
VOLTAGE"3.3V"
CDS_LMAN_SYM_OUTLINE"-250,250,250,-250"
CDS_LIB"cls"
BODY_TYPE"PLUMBING";
"$PIN0"3;
%"VCC"
"1","(-600,7050)","0","cls","I58";
;
HDL_POWER"XP3R3V_FPGA"
VOLTAGE"3.3V"
BODY_TYPE"PLUMBING"
CDS_LIB"cls"
CDS_LMAN_SYM_OUTLINE"-250,250,250,-250";
"$PIN0"11;
%"LM75BDP_TSSOP8"
"1","(-2700,4650)","0","interface","I59";
;
$LOCATION"U35"
CDS_LOCATION"U35"
$SEC"1"
CDS_SEC"1"
CLS_PN"G220-10215-01"
PART_NUMBER"LM75BDP,118"
CDS_LMAN_SYM_OUTLINE"0,0,500,-800"
CDS_LIB"interface";
"A0"
$PN"7"27;
"A1"
$PN"6"30;
"A2"
$PN"5"31;
"OS"
$PN"3"6;
"SCL"
$PN"2"20;
"SDA"
$PN"1"23;
%"RESISTOR"
"2","(-3400,3750)","0","passive","I60";
;
$LOCATION"R413"
CDS_LOCATION"R413"
$SEC"1"
CDS_SEC"1"
VALUE"1KOHM"
PACKAGE"0402"
TOLERANCE"1%"
CLS_PN"G155-11001-01"
CDS_LMAN_SYM_OUTLINE"-50,50,50,-100"
CDS_LIB"passive";
"1"
$PN"1"30;
"2"
$PN"2"13;
%"VCC"
"1","(-1200,5000)","0","cls","I62";
;
HDL_POWER"XP3R3V_FPGA"
VOLTAGE"3.3V"
BODY_TYPE"PLUMBING"
CDS_LMAN_SYM_OUTLINE"-250,250,250,-250"
CDS_LIB"cls";
"$PIN0"2;
%"VCC"
"1","(-600,3900)","0","cls","I63";
;
VOLTAGE"3.3V"
HDL_POWER"XP3R3V_FPGA"
BODY_TYPE"PLUMBING"
CDS_LMAN_SYM_OUTLINE"-250,250,250,-250"
CDS_LIB"cls";
"$PIN0"5;
%"RESISTOR"
"2","(-1150,4750)","0","passive","I64";
;
$LOCATION"R422"
CDS_LOCATION"R422"
$SEC"1"
CDS_SEC"1"
PACKAGE"0402"
VALUE"4.7KOHM"
TOLERANCE"1%"
CLS_PN"G155-14701-01"
CDS_LMAN_SYM_OUTLINE"-50,50,50,-100"
CDS_LIB"passive";
"1"
$PN"1"2;
"2"
$PN"2"6;
%"LM75BDP_TSSOP8"
"2","(-1050,3950)","5","interface","I66";
;
$LOCATION"U36"
CDS_LOCATION"U36"
$SEC"2"
CDS_SEC"2"
CLS_PN"G220-10215-01"
CDS_LMAN_SYM_OUTLINE"0,0,400,-700"
CDS_LIB"interface";
"GND"
$PN"4"12;
"VCC"
$PN"8"5;
%"CAPACITOR"
"1","(-1450,3250)","0","passive","I67";
;
$LOCATION"C305"
CDS_LOCATION"C305"
$SEC"1"
CDS_SEC"1"
VOLTAGE"25V"
PACKAGE"0402"
VALUE"0.1UF"
CDS_LIB"passive"
CDS_LMAN_SYM_OUTLINE"0,50,50,-50"
CLS_PN"G105-0B104-EK"
TOLERANCE"10%";
"2"
$PN"2"5;
"1"
$PN"1"12;
%"GND_SG"
"1","(-2100,3000)","0","cls","I68";
;
HDL_POWER"SG"
BODY_TYPE"PLUMBING"
CDS_LMAN_SYM_OUTLINE"0,0,100,-50"
CDS_LIB"cls";
"SGND"12;
%"RESISTOR"
"2","(-3000,5000)","0","passive","I69";
;
$LOCATION"R418"
CDS_LOCATION"R418"
$SEC"1"
CDS_SEC"1"
VALUE"4.7KOHM"
PACKAGE"0402"
TOLERANCE"1%"
CLS_PN"G155-14701-01"
CDS_LMAN_SYM_OUTLINE"-50,50,50,-100"
CDS_LIB"passive";
"1"
$PN"1"14;
"2"
$PN"2"27;
%"RESISTOR"
"2","(-3400,5000)","0","passive","I70";
;
$LOCATION"R412"
CDS_LOCATION"R412"
$SEC"1"
CDS_SEC"1"
NO_ASSY"TRUE"
VALUE"4.7KOHM"
PACKAGE"0402"
TOLERANCE"1%"
CLS_PN"G155-14701-01"
CDS_LMAN_SYM_OUTLINE"-50,50,50,-100"
CDS_LIB"passive";
"1"
$PN"1"14;
"2"
$PN"2"30;
%"RESISTOR"
"2","(-3850,5000)","0","passive","I71";
;
$LOCATION"R408"
CDS_LOCATION"R408"
$SEC"1"
CDS_SEC"1"
VALUE"4.7KOHM"
PACKAGE"0402"
NO_ASSY"TRUE"
TOLERANCE"1%"
CLS_PN"G155-14701-01"
CDS_LMAN_SYM_OUTLINE"-50,50,50,-100"
CDS_LIB"passive";
"1"
$PN"1"14;
"2"
$PN"2"31;
%"RESISTOR"
"2","(-3020,3740)","0","passive","I72";
;
$LOCATION"R416"
CDS_LOCATION"R416"
$SEC"1"
CDS_SEC"1"
PACKAGE"0402"
VALUE"1KOHM"
NO_ASSY"TRUE"
TOLERANCE"1%"
CLS_PN"G155-11001-01"
CDS_LMAN_SYM_OUTLINE"-50,50,50,-100"
CDS_LIB"passive";
"1"
$PN"1"27;
"2"
$PN"2"13;
%"RESISTOR"
"2","(-3850,3750)","0","passive","I73";
;
$LOCATION"R409"
CDS_LOCATION"R409"
$SEC"1"
CDS_SEC"1"
PACKAGE"0402"
VALUE"1KOHM"
TOLERANCE"1%"
CLS_PN"G155-11001-01"
CDS_LMAN_SYM_OUTLINE"-50,50,50,-100"
CDS_LIB"passive";
"1"
$PN"1"31;
"2"
$PN"2"13;
%"GND_SG"
"1","(-3900,3300)","0","cls","I74";
;
HDL_POWER"SG"
BODY_TYPE"PLUMBING"
CDS_LMAN_SYM_OUTLINE"0,0,100,-50"
CDS_LIB"cls";
"SGND"13;
%"RESISTOR"
"1","(-5600,4450)","0","passive","I76";
;
$LOCATION"R406"
CDS_LOCATION"R406"
$SEC"1"
CDS_SEC"1"
VALUE"33OHM"
PACKAGE"0402"
TOLERANCE"1%"
CDS_LIB"passive"
CDS_LMAN_SYM_OUTLINE"-50,50,100,-50"
CLS_PN"G155-133R0-01";
"1"
$PN"1"24;
"2"
$PN"2"23;
%"VCC"
"1","(-3900,5450)","0","cls","I77";
;
HDL_POWER"XP3R3V_FPGA"
VOLTAGE"3.3V"
BODY_TYPE"PLUMBING"
CDS_LIB"cls"
CDS_LMAN_SYM_OUTLINE"-250,250,250,-250";
"$PIN0"14;
%"LM75BDP_TSSOP8"
"1","(-2700,1800)","0","interface","I81";
;
$LOCATION"U36"
CDS_LOCATION"U36"
$SEC"1"
CDS_SEC"1"
CLS_PN"G220-10215-01"
PART_NUMBER"LM75BDP,118"
CDS_LMAN_SYM_OUTLINE"0,0,500,-800"
CDS_LIB"interface";
"A0"
$PN"7"21;
"A1"
$PN"6"29;
"A2"
$PN"5"28;
"OS"
$PN"3"7;
"SCL"
$PN"2"20;
"SDA"
$PN"1"19;
%"VCC"
"1","(-1250,2150)","0","cls","I83";
;
HDL_POWER"XP3R3V_FPGA"
VOLTAGE"3.3V"
CDS_LIB"cls"
CDS_LMAN_SYM_OUTLINE"-250,250,250,-250"
BODY_TYPE"PLUMBING";
"$PIN0"1;
%"RESISTOR"
"2","(-3000,2150)","0","passive","I84";
;
$LOCATION"R419"
CDS_LOCATION"R419"
$SEC"1"
CDS_SEC"1"
VALUE"4.7KOHM"
PACKAGE"0402"
NO_ASSY"TRUE"
TOLERANCE"1%"
CLS_PN"G155-14701-01"
CDS_LMAN_SYM_OUTLINE"-50,50,50,-100"
CDS_LIB"passive";
"1"
$PN"1"18;
"2"
$PN"2"21;
%"RESISTOR"
"2","(-3400,2150)","0","passive","I85";
;
$LOCATION"R414"
CDS_LOCATION"R414"
$SEC"1"
CDS_SEC"1"
VALUE"4.7KOHM"
PACKAGE"0402"
TOLERANCE"1%"
CLS_PN"G155-14701-01"
CDS_LMAN_SYM_OUTLINE"-50,50,50,-100"
CDS_LIB"passive";
"1"
$PN"1"18;
"2"
$PN"2"29;
%"RESISTOR"
"2","(-3850,2150)","0","passive","I86";
;
$LOCATION"R410"
CDS_LOCATION"R410"
$SEC"1"
CDS_SEC"1"
VALUE"4.7KOHM"
PACKAGE"0402"
NO_ASSY"TRUE"
TOLERANCE"1%"
CLS_PN"G155-14701-01"
CDS_LMAN_SYM_OUTLINE"-50,50,50,-100"
CDS_LIB"passive";
"1"
$PN"1"18;
"2"
$PN"2"28;
%"VCC"
"1","(-600,1050)","0","cls","I87";
;
VOLTAGE"3.3V"
HDL_POWER"XP3R3V_FPGA"
BODY_TYPE"PLUMBING"
CDS_LMAN_SYM_OUTLINE"-250,250,250,-250"
CDS_LIB"cls";
"$PIN0"15;
%"RESISTOR"
"2","(-1200,1900)","0","passive","I88";
;
$LOCATION"R423"
CDS_LOCATION"R423"
$SEC"1"
CDS_SEC"1"
PACKAGE"0402"
VALUE"4.7KOHM"
CDS_LIB"passive"
CDS_LMAN_SYM_OUTLINE"-50,50,50,-100"
CLS_PN"G155-14701-01"
TOLERANCE"1%";
"1"
$PN"1"1;
"2"
$PN"2"7;
%"LM75BDP_TSSOP8"
"2","(-1050,1100)","5","interface","I90";
;
$LOCATION"U35"
CDS_LOCATION"U35"
$SEC"2"
CDS_SEC"2"
CLS_PN"G220-10215-01"
CDS_LMAN_SYM_OUTLINE"0,0,400,-700"
CDS_LIB"interface";
"GND"
$PN"4"16;
"VCC"
$PN"8"15;
%"CAPACITOR"
"1","(-1450,400)","0","passive","I91";
;
$LOCATION"C306"
CDS_LOCATION"C306"
$SEC"1"
CDS_SEC"1"
VOLTAGE"25V"
PACKAGE"0402"
VALUE"0.1UF"
CDS_LIB"passive"
CDS_LMAN_SYM_OUTLINE"0,50,50,-50"
CLS_PN"G105-0B104-EK"
TOLERANCE"10%";
"2"
$PN"2"15;
"1"
$PN"1"16;
%"GND_SG"
"1","(-2100,150)","0","cls","I92";
;
HDL_POWER"SG"
BODY_TYPE"PLUMBING"
CDS_LMAN_SYM_OUTLINE"0,0,100,-50"
CDS_LIB"cls";
"SGND"16;
%"RESISTOR"
"2","(-3020,890)","0","passive","I93";
;
$LOCATION"R417"
CDS_LOCATION"R417"
$SEC"1"
CDS_SEC"1"
VALUE"1KOHM"
PACKAGE"0402"
TOLERANCE"1%"
CLS_PN"G155-11001-01"
CDS_LMAN_SYM_OUTLINE"-50,50,50,-100"
CDS_LIB"passive";
"1"
$PN"1"21;
"2"
$PN"2"17;
%"RESISTOR"
"2","(-3400,900)","0","passive","I94";
;
$LOCATION"R415"
CDS_LOCATION"R415"
$SEC"1"
CDS_SEC"1"
VALUE"1KOHM"
PACKAGE"0402"
NO_ASSY"TRUE"
TOLERANCE"1%"
CLS_PN"G155-11001-01"
CDS_LMAN_SYM_OUTLINE"-50,50,50,-100"
CDS_LIB"passive";
"1"
$PN"1"29;
"2"
$PN"2"17;
%"RESISTOR"
"2","(-3850,900)","0","passive","I95";
;
$LOCATION"R411"
CDS_LOCATION"R411"
$SEC"1"
CDS_SEC"1"
PACKAGE"0402"
VALUE"1KOHM"
TOLERANCE"1%"
CLS_PN"G155-11001-01"
CDS_LMAN_SYM_OUTLINE"-50,50,50,-100"
CDS_LIB"passive";
"1"
$PN"1"28;
"2"
$PN"2"17;
%"GND_SG"
"1","(-3900,450)","0","cls","I96";
;
HDL_POWER"SG"
BODY_TYPE"PLUMBING"
CDS_LMAN_SYM_OUTLINE"0,0,100,-50"
CDS_LIB"cls";
"SGND"17;
%"VCC"
"1","(-3900,2550)","0","cls","I98";
;
VOLTAGE"3.3V"
HDL_POWER"XP3R3V_FPGA"
BODY_TYPE"PLUMBING"
CDS_LIB"cls"
CDS_LMAN_SYM_OUTLINE"-250,250,250,-250";
"$PIN0"18;
END.
